FILE_TYPE = CONNECTIVITY;
{Allegro Design Entry HDL 17.2-2016 S081 (4005846) 1/11/2022}
"PAGE_NUMBER" = 284;
0"NC";
END.
